(kicad_pcb
	(version 20260206)
	(generator "pcbnew")
	(generator_version "10.0")
	(general
		(thickness 1.6)
		(legacy_teardrops no)
	)
	(paper "A4")
	(title_block
		(title "panther-plus-userver — 13130-1b_20150205.brd")
		(comment 1 "Honey Badger (Wiwynn) / footprints 1226-1233 of 1509")
	)
	(layers
		(0 "F.Cu" signal "TOP")
		(4 "In1.Cu" signal "L2")
		(6 "In2.Cu" signal "L3")
		(8 "In3.Cu" signal "L4")
		(10 "In4.Cu" signal "L5")
		(12 "In5.Cu" signal "L6")
		(14 "In6.Cu" signal "L7")
		(16 "In7.Cu" signal "L8")
		(18 "In8.Cu" signal "L9")
		(20 "In9.Cu" signal "L10")
		(22 "In10.Cu" signal "L11")
		(2 "B.Cu" signal "BOTTOM")
		(9 "F.Adhes" user "F.Adhesive")
		(11 "B.Adhes" user "B.Adhesive")
		(13 "F.Paste" user "Package Geometry/Pastemask Top")
		(15 "B.Paste" user "Package Geometry/Pastemask Bottom")
		(5 "F.SilkS" user "Ref Des/Silkscreen Top")
		(7 "B.SilkS" user "Ref Des/Silkscreen Bottom")
		(1 "F.Mask" user "Board Geometry/Soldermask Top")
		(3 "B.Mask" user "Board Geometry/Soldermask Bottom")
		(17 "Dwgs.User" user "User.Drawings")
		(19 "Cmts.User" user "User.Comments")
		(21 "Eco1.User" user "User.Eco1")
		(23 "Eco2.User" user "User.Eco2")
		(25 "Edge.Cuts" user "Board Geometry/Outline")
		(27 "Margin" user)
		(31 "F.CrtYd" user "Package Geometry/Place Bound Top")
		(29 "B.CrtYd" user "Package Geometry/Place Bound Bottom")
		(35 "F.Fab" user "Ref Des/Assembly Top")
		(33 "B.Fab" user "Ref Des/Assembly Bottom")
	)
	(footprint ""
		(layer "B.Cu")
		(at 65.4812 -22.479)
		(property "Reference" "R158"
			(at 0 0 0)
			(layer "B.SilkS")
			(hide yes)
			(effects
				(font
					(size 1.27 1.27)
				)
				(justify mirror)
			)
		)
		(property "Value" "4K7R2F-GP"
			(at -1.7907 -1.1176 0)
			(unlocked yes)
			(layer "B.Fab")
			(hide yes)
			(effects
				(font
					(size 1.016 1.016)
					(thickness 0.1524)
				)
				(justify mirror)
			)
		)
		(property "Device Type" "R402H16"
			(at -1.7907 -2.6416 0)
			(unlocked yes)
			(layer "B.Fab")
			(hide yes)
			(effects
				(font
					(size 1.016 1.016)
					(thickness 0.1524)
				)
				(justify mirror)
			)
		)
		(duplicate_pad_numbers_are_jumpers no)
		(fp_rect
			(start 0.381 0.8382)
			(end -0.381 -0.8382)
			(stroke
				(width 0)
				(type default)
			)
			(fill no)
			(layer "B.CrtYd")
		)
		(fp_rect
			(start 0.381 0.8382)
			(end -0.381 -0.8382)
			(stroke
				(width 0)
				(type default)
			)
			(fill no)
			(layer "B.Fab")
		)
		(pad "1" smd custom
			(at 0 -0.4318 180)
			(size 0.127 0.127)
			(layers "B.Cu" "B.Mask" "B.Paste")
			(net "P3V3")
			(options
				(clearance outline)
				(anchor circle)
			)
			(primitives
				(gr_poly
					(pts
						(arc
							(start -0.2032 0.2794)
							(mid -0.239121 0.264521)
							(end -0.254 0.2286)
						)
						(arc
							(start -0.254 -0.2286)
							(mid -0.239121 -0.264521)
							(end -0.2032 -0.2794)
						)
						(arc
							(start 0.2032 -0.2794)
							(mid 0.239121 -0.264521)
							(end 0.254 -0.2286)
						)
						(arc
							(start 0.254 0.2286)
							(mid 0.239121 0.264521)
							(end 0.2032 0.2794)
						)
					)
					(width 0)
					(fill yes)
				)
			)
		)
		(pad "2" smd custom
			(at 0 0.4318 180)
			(size 0.127 0.127)
			(layers "B.Cu" "B.Mask" "B.Paste")
			(net "MSATA_ACT#")
			(options
				(clearance outline)
				(anchor circle)
			)
			(primitives
				(gr_poly
					(pts
						(arc
							(start -0.2032 0.2794)
							(mid -0.239121 0.264521)
							(end -0.254 0.2286)
						)
						(arc
							(start -0.254 -0.2286)
							(mid -0.239121 -0.264521)
							(end -0.2032 -0.2794)
						)
						(arc
							(start 0.2032 -0.2794)
							(mid 0.239121 -0.264521)
							(end 0.254 -0.2286)
						)
						(arc
							(start 0.254 0.2286)
							(mid 0.239121 0.264521)
							(end 0.2032 0.2794)
						)
					)
					(width 0)
					(fill yes)
				)
			)
		)
	)
	(footprint ""
		(layer "B.Cu")
		(at 69.977 -61.722)
		(property "Reference" "C79"
			(at 0 0 0)
			(layer "B.SilkS")
			(hide yes)
			(effects
				(font
					(size 1.27 1.27)
				)
				(justify mirror)
			)
		)
		(property "Value" "SCD1U16V2KX-3GP"
			(at -1.8923 -1.2065 0)
			(unlocked yes)
			(layer "B.Fab")
			(hide yes)
			(effects
				(font
					(size 1.016 1.016)
					(thickness 0.1524)
				)
				(justify mirror)
			)
		)
		(property "Device Type" "C402H22"
			(at -1.8923 -2.7305 0)
			(unlocked yes)
			(layer "B.Fab")
			(hide yes)
			(effects
				(font
					(size 1.016 1.016)
					(thickness 0.1524)
				)
				(justify mirror)
			)
		)
		(duplicate_pad_numbers_are_jumpers no)
		(fp_rect
			(start 0.381 0.7366)
			(end -0.381 -0.7366)
			(stroke
				(width 0)
				(type default)
			)
			(fill no)
			(layer "B.CrtYd")
		)
		(fp_rect
			(start 0.381 0.7366)
			(end -0.381 -0.7366)
			(stroke
				(width 0)
				(type default)
			)
			(fill no)
			(layer "B.Fab")
		)
		(pad "1" smd custom
			(at 0 -0.4572 180)
			(size 0.1143 0.1143)
			(layers "B.Cu" "B.Mask" "B.Paste")
			(net "P3V3_STBY_SENSE")
			(options
				(clearance outline)
				(anchor circle)
			)
			(primitives
				(gr_poly
					(pts
						(arc
							(start -0.254 0.1778)
							(mid -0.239121 0.213721)
							(end -0.2032 0.2286)
						)
						(arc
							(start 0.2032 0.2286)
							(mid 0.239121 0.213721)
							(end 0.254 0.1778)
						)
						(arc
							(start 0.254 -0.1778)
							(mid 0.239121 -0.213721)
							(end 0.2032 -0.2286)
						)
						(arc
							(start -0.2032 -0.2286)
							(mid -0.239121 -0.213721)
							(end -0.254 -0.1778)
						)
					)
					(width 0)
					(fill yes)
				)
			)
		)
		(pad "2" smd custom
			(at 0 0.4572 180)
			(size 0.1143 0.1143)
			(layers "B.Cu" "B.Mask" "B.Paste")
			(net "GND")
			(options
				(clearance outline)
				(anchor circle)
			)
			(primitives
				(gr_poly
					(pts
						(arc
							(start -0.254 0.1778)
							(mid -0.239121 0.213721)
							(end -0.2032 0.2286)
						)
						(arc
							(start 0.2032 0.2286)
							(mid 0.239121 0.213721)
							(end 0.254 0.1778)
						)
						(arc
							(start 0.254 -0.1778)
							(mid 0.239121 -0.213721)
							(end 0.2032 -0.2286)
						)
						(arc
							(start -0.2032 -0.2286)
							(mid -0.239121 -0.213721)
							(end -0.254 -0.1778)
						)
					)
					(width 0)
					(fill yes)
				)
			)
		)
	)
	(footprint ""
		(layer "B.Cu")
		(at 196.85 -4.6736 180)
		(property "Reference" "R383"
			(at 0 0 0)
			(layer "B.SilkS")
			(hide yes)
			(effects
				(font
					(size 1.27 1.27)
				)
				(justify mirror)
			)
		)
		(property "Value" "0R2J-2-GP"
			(at -0.064008 -3.993896 180)
			(unlocked yes)
			(layer "B.Fab")
			(hide yes)
			(effects
				(font
					(size 1.016 1.016)
					(thickness 0.1524)
				)
				(justify mirror)
			)
		)
		(property "Device Type" "R402H16"
			(at -0.064008 -5.517896 180)
			(unlocked yes)
			(layer "B.Fab")
			(hide yes)
			(effects
				(font
					(size 1.016 1.016)
					(thickness 0.1524)
				)
				(justify mirror)
			)
		)
		(duplicate_pad_numbers_are_jumpers no)
		(fp_rect
			(start 0.381 0.8382)
			(end -0.381 -0.8382)
			(stroke
				(width 0)
				(type default)
			)
			(fill no)
			(layer "B.CrtYd")
		)
		(fp_rect
			(start 0.381 0.8382)
			(end -0.381 -0.8382)
			(stroke
				(width 0)
				(type default)
			)
			(fill no)
			(layer "B.Fab")
		)
		(pad "1" smd custom
			(at 0 -0.4318)
			(size 0.127 0.127)
			(layers "B.Cu" "B.Mask" "B.Paste")
			(net "SMB_M_B0_R_CLK")
			(options
				(clearance outline)
				(anchor circle)
			)
			(primitives
				(gr_poly
					(pts
						(arc
							(start -0.2032 0.2794)
							(mid -0.239121 0.264521)
							(end -0.254 0.2286)
						)
						(arc
							(start -0.254 -0.2286)
							(mid -0.239121 -0.264521)
							(end -0.2032 -0.2794)
						)
						(arc
							(start 0.2032 -0.2794)
							(mid 0.239121 -0.264521)
							(end 0.254 -0.2286)
						)
						(arc
							(start 0.254 0.2286)
							(mid 0.239121 0.264521)
							(end 0.2032 0.2794)
						)
					)
					(width 0)
					(fill yes)
				)
			)
		)
		(pad "2" smd custom
			(at 0 0.4318)
			(size 0.127 0.127)
			(layers "B.Cu" "B.Mask" "B.Paste")
			(net "SMB_HOST_LV_CLK")
			(options
				(clearance outline)
				(anchor circle)
			)
			(primitives
				(gr_poly
					(pts
						(arc
							(start -0.2032 0.2794)
							(mid -0.239121 0.264521)
							(end -0.254 0.2286)
						)
						(arc
							(start -0.254 -0.2286)
							(mid -0.239121 -0.264521)
							(end -0.2032 -0.2794)
						)
						(arc
							(start 0.2032 -0.2794)
							(mid 0.239121 -0.264521)
							(end 0.254 -0.2286)
						)
						(arc
							(start 0.254 0.2286)
							(mid 0.239121 0.264521)
							(end 0.2032 0.2794)
						)
					)
					(width 0)
					(fill yes)
				)
			)
		)
	)
	(footprint ""
		(layer "B.Cu")
		(at 186.69 -17.272 180)
		(property "Reference" "C291"
			(at 0 0 0)
			(layer "B.SilkS")
			(hide yes)
			(effects
				(font
					(size 1.27 1.27)
				)
				(justify mirror)
			)
		)
		(property "Value" "SC1U6D3V2KX-GP"
			(at -1.1811 -2.7051 180)
			(unlocked yes)
			(layer "B.Fab")
			(hide yes)
			(effects
				(font
					(size 1.016 1.016)
					(thickness 0.1524)
				)
				(justify mirror)
			)
		)
		(property "Device Type" "C402H22"
			(at -1.1811 -4.2291 180)
			(unlocked yes)
			(layer "B.Fab")
			(hide yes)
			(effects
				(font
					(size 1.016 1.016)
					(thickness 0.1524)
				)
				(justify mirror)
			)
		)
		(duplicate_pad_numbers_are_jumpers no)
		(fp_rect
			(start 0.381 0.7366)
			(end -0.381 -0.7366)
			(stroke
				(width 0)
				(type default)
			)
			(fill no)
			(layer "B.CrtYd")
		)
		(fp_rect
			(start 0.381 0.7366)
			(end -0.381 -0.7366)
			(stroke
				(width 0)
				(type default)
			)
			(fill no)
			(layer "B.Fab")
		)
		(pad "1" smd custom
			(at 0 -0.4572)
			(size 0.1143 0.1143)
			(layers "B.Cu" "B.Mask" "B.Paste")
			(net "PV_VTT_DDR_B")
			(options
				(clearance outline)
				(anchor circle)
			)
			(primitives
				(gr_poly
					(pts
						(arc
							(start -0.254 0.1778)
							(mid -0.239121 0.213721)
							(end -0.2032 0.2286)
						)
						(arc
							(start 0.2032 0.2286)
							(mid 0.239121 0.213721)
							(end 0.254 0.1778)
						)
						(arc
							(start 0.254 -0.1778)
							(mid 0.239121 -0.213721)
							(end 0.2032 -0.2286)
						)
						(arc
							(start -0.2032 -0.2286)
							(mid -0.239121 -0.213721)
							(end -0.254 -0.1778)
						)
					)
					(width 0)
					(fill yes)
				)
			)
		)
		(pad "2" smd custom
			(at 0 0.4572)
			(size 0.1143 0.1143)
			(layers "B.Cu" "B.Mask" "B.Paste")
			(net "GND")
			(options
				(clearance outline)
				(anchor circle)
			)
			(primitives
				(gr_poly
					(pts
						(arc
							(start -0.254 0.1778)
							(mid -0.239121 0.213721)
							(end -0.2032 0.2286)
						)
						(arc
							(start 0.2032 0.2286)
							(mid 0.239121 0.213721)
							(end 0.254 0.1778)
						)
						(arc
							(start 0.254 -0.1778)
							(mid 0.239121 -0.213721)
							(end 0.2032 -0.2286)
						)
						(arc
							(start -0.2032 -0.2286)
							(mid -0.239121 -0.213721)
							(end -0.254 -0.1778)
						)
					)
					(width 0)
					(fill yes)
				)
			)
		)
	)
	(footprint ""
		(layer "B.Cu")
		(at 71.501 -35.179 90)
		(property "Reference" "C191"
			(at 0 0 90)
			(layer "B.SilkS")
			(hide yes)
			(effects
				(font
					(size 1.27 1.27)
				)
				(justify mirror)
			)
		)
		(property "Value" "SC2D2U10V2KX-GP"
			(at -1.1811 -2.7051 90)
			(unlocked yes)
			(layer "B.Fab")
			(hide yes)
			(effects
				(font
					(size 1.016 1.016)
					(thickness 0.1524)
				)
				(justify mirror)
			)
		)
		(property "Device Type" "C402H22"
			(at -1.1811 -4.2291 90)
			(unlocked yes)
			(layer "B.Fab")
			(hide yes)
			(effects
				(font
					(size 1.016 1.016)
					(thickness 0.1524)
				)
				(justify mirror)
			)
		)
		(duplicate_pad_numbers_are_jumpers no)
		(fp_rect
			(start 0.381 0.7366)
			(end -0.381 -0.7366)
			(stroke
				(width 0)
				(type default)
			)
			(fill no)
			(layer "B.CrtYd")
		)
		(fp_rect
			(start 0.381 0.7366)
			(end -0.381 -0.7366)
			(stroke
				(width 0)
				(type default)
			)
			(fill no)
			(layer "B.Fab")
		)
		(pad "1" smd custom
			(at 0 -0.4572 270)
			(size 0.1143 0.1143)
			(layers "B.Cu" "B.Mask" "B.Paste")
			(net "SRTCRST_BUF_IN#")
			(options
				(clearance outline)
				(anchor circle)
			)
			(primitives
				(gr_poly
					(pts
						(arc
							(start -0.254 0.1778)
							(mid -0.239121 0.213721)
							(end -0.2032 0.2286)
						)
						(arc
							(start 0.2032 0.2286)
							(mid 0.239121 0.213721)
							(end 0.254 0.1778)
						)
						(arc
							(start 0.254 -0.1778)
							(mid 0.239121 -0.213721)
							(end 0.2032 -0.2286)
						)
						(arc
							(start -0.2032 -0.2286)
							(mid -0.239121 -0.213721)
							(end -0.254 -0.1778)
						)
					)
					(width 0)
					(fill yes)
				)
			)
		)
		(pad "2" smd custom
			(at 0 0.4572 270)
			(size 0.1143 0.1143)
			(layers "B.Cu" "B.Mask" "B.Paste")
			(net "GND")
			(options
				(clearance outline)
				(anchor circle)
			)
			(primitives
				(gr_poly
					(pts
						(arc
							(start -0.254 0.1778)
							(mid -0.239121 0.213721)
							(end -0.2032 0.2286)
						)
						(arc
							(start 0.2032 0.2286)
							(mid 0.239121 0.213721)
							(end 0.254 0.1778)
						)
						(arc
							(start 0.254 -0.1778)
							(mid 0.239121 -0.213721)
							(end 0.2032 -0.2286)
						)
						(arc
							(start -0.2032 -0.2286)
							(mid -0.239121 -0.213721)
							(end -0.254 -0.1778)
						)
					)
					(width 0)
					(fill yes)
				)
			)
		)
	)
	(footprint ""
		(layer "B.Cu")
		(at 74.168 -42.672 90)
		(property "Reference" "R308"
			(at 0 0 90)
			(layer "B.SilkS")
			(hide yes)
			(effects
				(font
					(size 1.27 1.27)
				)
				(justify mirror)
			)
		)
		(property "Value" "4K7R2F-GP"
			(at -0.064008 -3.993896 90)
			(unlocked yes)
			(layer "B.Fab")
			(hide yes)
			(effects
				(font
					(size 1.016 1.016)
					(thickness 0.1524)
				)
				(justify mirror)
			)
		)
		(property "Device Type" "R402H16"
			(at -0.064008 -5.517896 90)
			(unlocked yes)
			(layer "B.Fab")
			(hide yes)
			(effects
				(font
					(size 1.016 1.016)
					(thickness 0.1524)
				)
				(justify mirror)
			)
		)
		(duplicate_pad_numbers_are_jumpers no)
		(fp_rect
			(start 0.381 0.8382)
			(end -0.381 -0.8382)
			(stroke
				(width 0)
				(type default)
			)
			(fill no)
			(layer "B.CrtYd")
		)
		(fp_rect
			(start 0.381 0.8382)
			(end -0.381 -0.8382)
			(stroke
				(width 0)
				(type default)
			)
			(fill no)
			(layer "B.Fab")
		)
		(pad "1" smd custom
			(at 0 -0.4318 270)
			(size 0.127 0.127)
			(layers "B.Cu" "B.Mask" "B.Paste")
			(net "P3V3")
			(options
				(clearance outline)
				(anchor circle)
			)
			(primitives
				(gr_poly
					(pts
						(arc
							(start -0.2032 0.2794)
							(mid -0.239121 0.264521)
							(end -0.254 0.2286)
						)
						(arc
							(start -0.254 -0.2286)
							(mid -0.239121 -0.264521)
							(end -0.2032 -0.2794)
						)
						(arc
							(start 0.2032 -0.2794)
							(mid 0.239121 -0.264521)
							(end 0.254 -0.2286)
						)
						(arc
							(start 0.254 0.2286)
							(mid 0.239121 0.264521)
							(end 0.2032 0.2794)
						)
					)
					(width 0)
					(fill yes)
				)
			)
		)
		(pad "2" smd custom
			(at 0 0.4318 270)
			(size 0.127 0.127)
			(layers "B.Cu" "B.Mask" "B.Paste")
			(net "CPU_DIAG_LED")
			(options
				(clearance outline)
				(anchor circle)
			)
			(primitives
				(gr_poly
					(pts
						(arc
							(start -0.2032 0.2794)
							(mid -0.239121 0.264521)
							(end -0.254 0.2286)
						)
						(arc
							(start -0.254 -0.2286)
							(mid -0.239121 -0.264521)
							(end -0.2032 -0.2794)
						)
						(arc
							(start 0.2032 -0.2794)
							(mid 0.239121 -0.264521)
							(end 0.254 -0.2286)
						)
						(arc
							(start 0.254 0.2286)
							(mid 0.239121 0.264521)
							(end 0.2032 0.2794)
						)
					)
					(width 0)
					(fill yes)
				)
			)
		)
	)
	(footprint ""
		(layer "B.Cu")
		(at 116.078 -64.008 90)
		(property "Reference" "R402"
			(at 0 0 90)
			(layer "B.SilkS")
			(hide yes)
			(effects
				(font
					(size 1.27 1.27)
				)
				(justify mirror)
			)
		)
		(property "Value" "1KR2F-3-GP"
			(at -1.7907 -1.1176 90)
			(unlocked yes)
			(layer "B.Fab")
			(hide yes)
			(effects
				(font
					(size 1.016 1.016)
					(thickness 0.1524)
				)
				(justify mirror)
			)
		)
		(property "Device Type" "R402H16"
			(at -1.7907 -2.6416 90)
			(unlocked yes)
			(layer "B.Fab")
			(hide yes)
			(effects
				(font
					(size 1.016 1.016)
					(thickness 0.1524)
				)
				(justify mirror)
			)
		)
		(duplicate_pad_numbers_are_jumpers no)
		(fp_rect
			(start 0.381 0.8382)
			(end -0.381 -0.8382)
			(stroke
				(width 0)
				(type default)
			)
			(fill no)
			(layer "B.CrtYd")
		)
		(fp_rect
			(start 0.381 0.8382)
			(end -0.381 -0.8382)
			(stroke
				(width 0)
				(type default)
			)
			(fill no)
			(layer "B.Fab")
		)
		(pad "1" smd custom
			(at 0 -0.4318 270)
			(size 0.127 0.127)
			(layers "B.Cu" "B.Mask" "B.Paste")
			(net "P3V0_BAT")
			(options
				(clearance outline)
				(anchor circle)
			)
			(primitives
				(gr_poly
					(pts
						(arc
							(start -0.2032 0.2794)
							(mid -0.239121 0.264521)
							(end -0.254 0.2286)
						)
						(arc
							(start -0.254 -0.2286)
							(mid -0.239121 -0.264521)
							(end -0.2032 -0.2794)
						)
						(arc
							(start 0.2032 -0.2794)
							(mid 0.239121 -0.264521)
							(end 0.254 -0.2286)
						)
						(arc
							(start 0.254 0.2286)
							(mid 0.239121 0.264521)
							(end 0.2032 0.2794)
						)
					)
					(width 0)
					(fill yes)
				)
			)
		)
		(pad "2" smd custom
			(at 0 0.4318 270)
			(size 0.127 0.127)
			(layers "B.Cu" "B.Mask" "B.Paste")
			(net "P3V0_BAT_R")
			(options
				(clearance outline)
				(anchor circle)
			)
			(primitives
				(gr_poly
					(pts
						(arc
							(start -0.2032 0.2794)
							(mid -0.239121 0.264521)
							(end -0.254 0.2286)
						)
						(arc
							(start -0.254 -0.2286)
							(mid -0.239121 -0.264521)
							(end -0.2032 -0.2794)
						)
						(arc
							(start 0.2032 -0.2794)
							(mid 0.239121 -0.264521)
							(end 0.254 -0.2286)
						)
						(arc
							(start 0.254 0.2286)
							(mid 0.239121 0.264521)
							(end 0.2032 0.2794)
						)
					)
					(width 0)
					(fill yes)
				)
			)
		)
	)
	(footprint ""
		(layer "B.Cu")
		(at 92.583 -33.02)
		(property "Reference" "C220"
			(at 0 0 0)
			(layer "B.SilkS")
			(hide yes)
			(effects
				(font
					(size 1.27 1.27)
				)
				(justify mirror)
			)
		)
		(property "Value" "SC1U10V2KX-1GP"
			(at -1.1811 -2.7051 0)
			(unlocked yes)
			(layer "B.Fab")
			(hide yes)
			(effects
				(font
					(size 1.016 1.016)
					(thickness 0.1524)
				)
				(justify mirror)
			)
		)
		(property "Device Type" "C402H22"
			(at -1.1811 -4.2291 0)
			(unlocked yes)
			(layer "B.Fab")
			(hide yes)
			(effects
				(font
					(size 1.016 1.016)
					(thickness 0.1524)
				)
				(justify mirror)
			)
		)
		(duplicate_pad_numbers_are_jumpers no)
		(fp_rect
			(start 0.381 0.7366)
			(end -0.381 -0.7366)
			(stroke
				(width 0)
				(type default)
			)
			(fill no)
			(layer "B.CrtYd")
		)
		(fp_rect
			(start 0.381 0.7366)
			(end -0.381 -0.7366)
			(stroke
				(width 0)
				(type default)
			)
			(fill no)
			(layer "B.Fab")
		)
		(pad "1" smd custom
			(at 0 -0.4572 180)
			(size 0.1143 0.1143)
			(layers "B.Cu" "B.Mask" "B.Paste")
			(net "P1V0_STBY")
			(options
				(clearance outline)
				(anchor circle)
			)
			(primitives
				(gr_poly
					(pts
						(arc
							(start -0.254 0.1778)
							(mid -0.239121 0.213721)
							(end -0.2032 0.2286)
						)
						(arc
							(start 0.2032 0.2286)
							(mid 0.239121 0.213721)
							(end 0.254 0.1778)
						)
						(arc
							(start 0.254 -0.1778)
							(mid 0.239121 -0.213721)
							(end 0.2032 -0.2286)
						)
						(arc
							(start -0.2032 -0.2286)
							(mid -0.239121 -0.213721)
							(end -0.254 -0.1778)
						)
					)
					(width 0)
					(fill yes)
				)
			)
		)
		(pad "2" smd custom
			(at 0 0.4572 180)
			(size 0.1143 0.1143)
			(layers "B.Cu" "B.Mask" "B.Paste")
			(net "GND")
			(options
				(clearance outline)
				(anchor circle)
			)
			(primitives
				(gr_poly
					(pts
						(arc
							(start -0.254 0.1778)
							(mid -0.239121 0.213721)
							(end -0.2032 0.2286)
						)
						(arc
							(start 0.2032 0.2286)
							(mid 0.239121 0.213721)
							(end 0.254 0.1778)
						)
						(arc
							(start 0.254 -0.1778)
							(mid 0.239121 -0.213721)
							(end 0.2032 -0.2286)
						)
						(arc
							(start -0.2032 -0.2286)
							(mid -0.239121 -0.213721)
							(end -0.254 -0.1778)
						)
					)
					(width 0)
					(fill yes)
				)
			)
		)
	)
)
